# S9S_MB_2U (Grand Teton) — schematic netlist excerpt (pin names and nets, part order shuffled) for the footprints in the layout excerpt that follows; sources: Cadence DE-HDL packaged netlist, KiCad conversion of 03242023_DA0F0TMBIJ0_F0T_Motherboard_J_brd_V01_OCP.brd

R538  Q_RES  10K 1% EMPTY  pkg 0402LF  page 231 : A = P3V3_AUX ; B = PCA9548_PCIE3_ADDR1
R2704  Q_RES  0 5% CHIP  pkg 0402LF  page 231 : A = SMB_BMC_SWB_SDA_R4 ; B = SMB_BMC_SWB_SDA

(kicad_pcb
	(version 20260206)
	(generator "pcbnew")
	(generator_version "10.0")
	(general
		(thickness 1.6)
		(legacy_teardrops no)
	)
	(paper "A4")
	(title_block
		(title "03242023_DA0F0TMBIJ0_F0T_Motherboard_J_brd_V01_OCP.brd")
		(comment 1 "Grand Teton / footprints 313-314 of 6105")
	)
	(layers
		(0 "F.Cu" signal "TOP")
		(4 "In1.Cu" signal "GND")
		(6 "In2.Cu" signal "IN1")
		(8 "In3.Cu" signal "GND1")
		(10 "In4.Cu" signal "IN2")
		(12 "In5.Cu" signal "GND2")
		(14 "In6.Cu" signal "IN3")
		(16 "In7.Cu" signal "GND3")
		(18 "In8.Cu" signal "VCC")
		(20 "In9.Cu" signal "VCC1")
		(22 "In10.Cu" signal "GND4")
		(24 "In11.Cu" signal "IN4")
		(26 "In12.Cu" signal "GND5")
		(28 "In13.Cu" signal "IN5")
		(30 "In14.Cu" signal "GND6")
		(32 "In15.Cu" signal "IN6")
		(34 "In16.Cu" signal "GND7")
		(2 "B.Cu" signal "BOTTOM")
		(9 "F.Adhes" user "F.Adhesive")
		(11 "B.Adhes" user "B.Adhesive")
		(13 "F.Paste" user "Package Geometry/Pastemask Top")
		(15 "B.Paste" user "Package Geometry/Pastemask Bottom")
		(5 "F.SilkS" user "Ref Des/Silkscreen Top")
		(7 "B.SilkS" user "Ref Des/Silkscreen Bottom")
		(1 "F.Mask" user "Board Geometry/Soldermask Top")
		(3 "B.Mask" user "Board Geometry/Soldermask Bottom")
		(17 "Dwgs.User" user "User.Drawings")
		(19 "Cmts.User" user "User.Comments")
		(21 "Eco1.User" user "User.Eco1")
		(23 "Eco2.User" user "User.Eco2")
		(25 "Edge.Cuts" user "Board Geometry/Outline")
		(27 "Margin" user)
		(31 "F.CrtYd" user "Package Geometry/Place Bound Top")
		(29 "B.CrtYd" user "Package Geometry/Place Bound Bottom")
		(35 "F.Fab" user "Ref Des/Assembly Top")
		(33 "B.Fab" user "Ref Des/Assembly Bottom")
	)
	(footprint ""
		(layer "F.Cu")
		(at 128.401572 -128.986026)
		(property "Reference" "R2704"
			(at 0 0 0)
			(layer "F.SilkS")
			(hide yes)
			(effects
				(font
					(size 1.27 1.27)
				)
			)
		)
		(property "Value" ""
			(at 0 0 0)
			(layer "F.Fab")
			(effects
				(font
					(size 1.27 1.27)
				)
			)
		)
		(duplicate_pad_numbers_are_jumpers no)
		(fp_line
			(start -0.7874 -0.4064)
			(end 0.7874 -0.4064)
			(stroke
				(width 0.1524)
				(type default)
			)
			(layer "F.SilkS")
		)
		(fp_line
			(start -0.7874 0.4064)
			(end -0.7874 -0.4064)
			(stroke
				(width 0.1524)
				(type default)
			)
			(layer "F.SilkS")
		)
		(fp_line
			(start 0.7874 -0.4064)
			(end 0.7874 0.4064)
			(stroke
				(width 0.1524)
				(type default)
			)
			(layer "F.SilkS")
		)
		(fp_line
			(start 0.7874 0.4064)
			(end -0.7874 0.4064)
			(stroke
				(width 0.1524)
				(type default)
			)
			(layer "F.SilkS")
		)
		(fp_line
			(start -0.67945 -0.305054)
			(end -0.12065 -0.305054)
			(stroke
				(width 0.1)
				(type default)
			)
			(layer "F.Fab")
		)
		(fp_line
			(start -0.67945 0.3048)
			(end -0.67945 -0.305054)
			(stroke
				(width 0.1)
				(type default)
			)
			(layer "F.Fab")
		)
		(fp_line
			(start -0.12065 -0.305054)
			(end -0.12065 -0.2794)
			(stroke
				(width 0.1)
				(type default)
			)
			(layer "F.Fab")
		)
		(fp_line
			(start -0.12065 -0.2794)
			(end 0.12065 -0.2794)
			(stroke
				(width 0.1)
				(type default)
			)
			(layer "F.Fab")
		)
		(fp_line
			(start -0.12065 0.2794)
			(end -0.12065 0.3048)
			(stroke
				(width 0.1)
				(type default)
			)
			(layer "F.Fab")
		)
		(fp_line
			(start -0.12065 0.3048)
			(end -0.67945 0.3048)
			(stroke
				(width 0.1)
				(type default)
			)
			(layer "F.Fab")
		)
		(fp_line
			(start 0.120396 0.2794)
			(end -0.12065 0.2794)
			(stroke
				(width 0.1)
				(type default)
			)
			(layer "F.Fab")
		)
		(fp_line
			(start 0.120396 0.3048)
			(end 0.120396 0.2794)
			(stroke
				(width 0.1)
				(type default)
			)
			(layer "F.Fab")
		)
		(fp_line
			(start 0.12065 -0.3048)
			(end 0.67945 -0.3048)
			(stroke
				(width 0.1)
				(type default)
			)
			(layer "F.Fab")
		)
		(fp_line
			(start 0.12065 -0.2794)
			(end 0.12065 -0.3048)
			(stroke
				(width 0.1)
				(type default)
			)
			(layer "F.Fab")
		)
		(fp_line
			(start 0.67945 -0.3048)
			(end 0.67945 0.3048)
			(stroke
				(width 0.1)
				(type default)
			)
			(layer "F.Fab")
		)
		(fp_line
			(start 0.67945 0.3048)
			(end 0.120396 0.3048)
			(stroke
				(width 0.1)
				(type default)
			)
			(layer "F.Fab")
		)
		(pad "1" smd circle
			(at -0.40005 0)
			(size 0 0)
			(layers "F.Cu" "F.Mask" "F.Paste")
			(net "SMB_BMC_SWB_SDA_R4")
		)
		(pad "2" smd circle
			(at 0.40005 0)
			(size 0 0)
			(layers "F.Cu" "F.Mask" "F.Paste")
			(net "SMB_BMC_SWB_SDA")
		)
	)
	(footprint ""
		(layer "F.Cu")
		(at 111.332772 -139.133326)
		(property "Reference" "R538"
			(at 0 0 0)
			(layer "F.SilkS")
			(hide yes)
			(effects
				(font
					(size 1.27 1.27)
				)
			)
		)
		(property "Value" ""
			(at 0 0 0)
			(layer "F.Fab")
			(effects
				(font
					(size 1.27 1.27)
				)
			)
		)
		(duplicate_pad_numbers_are_jumpers no)
		(fp_line
			(start -0.7874 -0.4064)
			(end 0.7874 -0.4064)
			(stroke
				(width 0.1524)
				(type default)
			)
			(layer "F.SilkS")
		)
		(fp_line
			(start -0.7874 0.4064)
			(end -0.7874 -0.4064)
			(stroke
				(width 0.1524)
				(type default)
			)
			(layer "F.SilkS")
		)
		(fp_line
			(start 0.7874 -0.4064)
			(end 0.7874 0.4064)
			(stroke
				(width 0.1524)
				(type default)
			)
			(layer "F.SilkS")
		)
		(fp_line
			(start 0.7874 0.4064)
			(end -0.7874 0.4064)
			(stroke
				(width 0.1524)
				(type default)
			)
			(layer "F.SilkS")
		)
		(fp_line
			(start -0.67945 -0.305054)
			(end -0.12065 -0.305054)
			(stroke
				(width 0.1)
				(type default)
			)
			(layer "F.Fab")
		)
		(fp_line
			(start -0.67945 0.3048)
			(end -0.67945 -0.305054)
			(stroke
				(width 0.1)
				(type default)
			)
			(layer "F.Fab")
		)
		(fp_line
			(start -0.12065 -0.305054)
			(end -0.12065 -0.2794)
			(stroke
				(width 0.1)
				(type default)
			)
			(layer "F.Fab")
		)
		(fp_line
			(start -0.12065 -0.2794)
			(end 0.12065 -0.2794)
			(stroke
				(width 0.1)
				(type default)
			)
			(layer "F.Fab")
		)
		(fp_line
			(start -0.12065 0.2794)
			(end -0.12065 0.3048)
			(stroke
				(width 0.1)
				(type default)
			)
			(layer "F.Fab")
		)
		(fp_line
			(start -0.12065 0.3048)
			(end -0.67945 0.3048)
			(stroke
				(width 0.1)
				(type default)
			)
			(layer "F.Fab")
		)
		(fp_line
			(start 0.120396 0.2794)
			(end -0.12065 0.2794)
			(stroke
				(width 0.1)
				(type default)
			)
			(layer "F.Fab")
		)
		(fp_line
			(start 0.120396 0.3048)
			(end 0.120396 0.2794)
			(stroke
				(width 0.1)
				(type default)
			)
			(layer "F.Fab")
		)
		(fp_line
			(start 0.12065 -0.3048)
			(end 0.67945 -0.3048)
			(stroke
				(width 0.1)
				(type default)
			)
			(layer "F.Fab")
		)
		(fp_line
			(start 0.12065 -0.2794)
			(end 0.12065 -0.3048)
			(stroke
				(width 0.1)
				(type default)
			)
			(layer "F.Fab")
		)
		(fp_line
			(start 0.67945 -0.3048)
			(end 0.67945 0.3048)
			(stroke
				(width 0.1)
				(type default)
			)
			(layer "F.Fab")
		)
		(fp_line
			(start 0.67945 0.3048)
			(end 0.120396 0.3048)
			(stroke
				(width 0.1)
				(type default)
			)
			(layer "F.Fab")
		)
		(pad "1" smd circle
			(at -0.40005 0)
			(size 0 0)
			(layers "F.Cu" "F.Mask" "F.Paste")
			(net "P3V3_AUX")
		)
		(pad "2" smd circle
			(at 0.40005 0)
			(size 0 0)
			(layers "F.Cu" "F.Mask" "F.Paste")
			(net "PCA9548_PCIE3_ADDR1")
		)
	)
)
